(kicad_pcb
	(version 20260206)
	(generator "pcbnew")
	(generator_version "10.0")
	(general
		(thickness 1.6)
		(legacy_teardrops no)
	)
	(paper "A4")
	(title_block
		(title "01162023_DA0F0TEBIF0_F0T_Expander_BD_F_brd_V02_OCP.brd")
		(comment 1 "Grand Teton / footprints 7443-7448 of 9728")
	)
	(layers
		(0 "F.Cu" signal "TOP")
		(4 "In1.Cu" signal "GND")
		(6 "In2.Cu" signal "VCC")
		(8 "In3.Cu" signal "VCC1")
		(10 "In4.Cu" signal "GND1")
		(12 "In5.Cu" signal "IN1")
		(14 "In6.Cu" signal "GND2")
		(16 "In7.Cu" signal "IN2")
		(18 "In8.Cu" signal "GND3")
		(20 "In9.Cu" signal "IN3")
		(22 "In10.Cu" signal "GND4")
		(24 "In11.Cu" signal "IN4")
		(26 "In12.Cu" signal "GND5")
		(28 "In13.Cu" signal "IN5")
		(30 "In14.Cu" signal "GND6")
		(32 "In15.Cu" signal "IN6")
		(34 "In16.Cu" signal "GND7")
		(2 "B.Cu" signal "BOTTOM")
		(9 "F.Adhes" user "F.Adhesive")
		(11 "B.Adhes" user "B.Adhesive")
		(13 "F.Paste" user "Package Geometry/Pastemask Top")
		(15 "B.Paste" user "Package Geometry/Pastemask Bottom")
		(5 "F.SilkS" user "Ref Des/Silkscreen Top")
		(7 "B.SilkS" user "Ref Des/Silkscreen Bottom")
		(1 "F.Mask" user "Board Geometry/Soldermask Top")
		(3 "B.Mask" user "Board Geometry/Soldermask Bottom")
		(17 "Dwgs.User" user "User.Drawings")
		(19 "Cmts.User" user "User.Comments")
		(21 "Eco1.User" user "User.Eco1")
		(23 "Eco2.User" user "User.Eco2")
		(25 "Edge.Cuts" user "Board Geometry/Outline")
		(27 "Margin" user)
		(31 "F.CrtYd" user "Package Geometry/Place Bound Top")
		(29 "B.CrtYd" user "Package Geometry/Place Bound Bottom")
		(35 "F.Fab" user "Ref Des/Assembly Top")
		(33 "B.Fab" user "Ref Des/Assembly Bottom")
	)
	(footprint ""
		(layer "B.Cu")
		(at 87.150448 -447.452496)
		(property "Reference" "X57"
			(at 0.1778 -1.92913 0)
			(unlocked yes)
			(layer "B.SilkS")
			(effects
				(font
					(size 0.7874 0.5842)
					(thickness 0.1524)
				)
				(justify left mirror)
			)
		)
		(property "Value" ""
			(at 0 0 0)
			(layer "B.Fab")
			(effects
				(font
					(size 1.27 1.27)
				)
				(justify mirror)
			)
		)
		(property "Device Type" "TP_TDR_4P_FTS_MPKT4_H025P0200_IO_TP15_TP_TDR_4P_DIP"
			(at -1.30175 1.27 270)
			(unlocked yes)
			(layer "B.Fab")
			(hide yes)
			(effects
				(font
					(size 0.635 0.4064)
					(thickness 0.1524)
				)
				(justify mirror)
			)
		)
		(property "User Part Number" "TP15"
			(at -1.30175 1.27 270)
			(unlocked yes)
			(layer "Cmts.User")
			(hide yes)
			(effects
				(font
					(size 0.635 0.4064)
					(thickness 0.1524)
				)
				(justify mirror)
			)
		)
		(duplicate_pad_numbers_are_jumpers no)
		(fp_line
			(start -2.54 -1.27)
			(end 0 -1.27)
			(stroke
				(width 0.1524)
				(type default)
			)
			(layer "B.SilkS")
		)
		(fp_line
			(start -2.54 -1.1303)
			(end -2.54 -1.27)
			(stroke
				(width 0.1524)
				(type default)
			)
			(layer "B.SilkS")
		)
		(fp_line
			(start -2.54 1.4097)
			(end -2.54 1.1303)
			(stroke
				(width 0.1524)
				(type default)
			)
			(layer "B.SilkS")
		)
		(fp_line
			(start -2.54 3.81)
			(end -2.54 3.6703)
			(stroke
				(width 0.1524)
				(type default)
			)
			(layer "B.SilkS")
		)
		(fp_line
			(start 0 -1.27)
			(end 0 -0.635)
			(stroke
				(width 0.1524)
				(type default)
			)
			(layer "B.SilkS")
		)
		(fp_line
			(start 0 0.635)
			(end 0 1.905)
			(stroke
				(width 0.1524)
				(type default)
			)
			(layer "B.SilkS")
		)
		(fp_line
			(start 0 3.175)
			(end 0 3.81)
			(stroke
				(width 0.1524)
				(type default)
			)
			(layer "B.SilkS")
		)
		(fp_line
			(start 0 3.81)
			(end -2.54 3.81)
			(stroke
				(width 0.1524)
				(type default)
			)
			(layer "B.SilkS")
		)
		(fp_poly
			(pts
				(xy 0.761746 0) (xy 2.285746 -0.762) (xy 2.285746 0.762)
			)
			(stroke
				(width 0)
				(type default)
			)
			(fill yes)
			(layer "B.SilkS")
		)
		(fp_line
			(start -2.54 -1.27)
			(end 0 -1.27)
			(stroke
				(width 0.1)
				(type default)
			)
			(layer "B.Fab")
		)
		(fp_line
			(start -2.54 3.81)
			(end -2.54 -1.27)
			(stroke
				(width 0.1)
				(type default)
			)
			(layer "B.Fab")
		)
		(fp_line
			(start 0 -1.27)
			(end 0 3.81)
			(stroke
				(width 0.1)
				(type default)
			)
			(layer "B.Fab")
		)
		(fp_line
			(start 0 3.81)
			(end -2.54 3.81)
			(stroke
				(width 0.1)
				(type default)
			)
			(layer "B.Fab")
		)
		(fp_poly
			(pts
				(xy 0.761746 0) (xy 2.285746 -0.762) (xy 2.285746 0.762)
			)
			(stroke
				(width 0)
				(type default)
			)
			(fill yes)
			(layer "B.Fab")
		)
		(pad "1" thru_hole circle
			(at 0 0 180)
			(size 1.0033 1.0033)
			(drill 0.249936)
			(layers "*.Cu" "*.Mask")
			(remove_unused_layers no)
			(net "TDR_DIFF_85_BOT_DIN")
			(clearance 0.10795)
			(padstack
				(mode front_inner_back)
				(layer "Inner"
					(shape circle)
					(size 0.8001 0.8001)
					(clearance 0.1524)
				)
				(layer "B.Cu"
					(shape circle)
					(size 1.0033 1.0033)
					(thermal_gap 0.10795)
					(clearance 0.10795)
				)
			)
		)
		(pad "2" thru_hole circle
			(at -2.54 0 180)
			(size 1.9939 1.9939)
			(drill 0.249936)
			(layers "*.Cu" "*.Mask")
			(remove_unused_layers no)
			(net "COUPON_GND1")
			(clearance 0.10795)
			(padstack
				(mode front_inner_back)
				(layer "Inner"
					(shape circle)
					(size 0.8001 0.8001)
					(clearance 0.1524)
				)
				(layer "B.Cu"
					(shape circle)
					(size 1.9939 1.9939)
					(thermal_gap 0.10795)
					(clearance 0.10795)
				)
			)
		)
		(pad "3" thru_hole circle
			(at -2.54 2.54 180)
			(size 1.9939 1.9939)
			(drill 0.249936)
			(layers "*.Cu" "*.Mask")
			(remove_unused_layers no)
			(net "COUPON_GND1")
			(clearance 0.10795)
			(padstack
				(mode front_inner_back)
				(layer "Inner"
					(shape circle)
					(size 0.8001 0.8001)
					(clearance 0.1524)
				)
				(layer "B.Cu"
					(shape circle)
					(size 1.9939 1.9939)
					(thermal_gap 0.10795)
					(clearance 0.10795)
				)
			)
		)
		(pad "4" thru_hole circle
			(at 0 2.54 180)
			(size 1.0033 1.0033)
			(drill 0.249936)
			(layers "*.Cu" "*.Mask")
			(remove_unused_layers no)
			(net "TDR_DIFF_85_BOT_DIP")
			(clearance 0.10795)
			(padstack
				(mode front_inner_back)
				(layer "Inner"
					(shape circle)
					(size 0.8001 0.8001)
					(clearance 0.1524)
				)
				(layer "B.Cu"
					(shape circle)
					(size 1.0033 1.0033)
					(thermal_gap 0.10795)
					(clearance 0.10795)
				)
			)
		)
	)
	(footprint ""
		(layer "B.Cu")
		(at 413.649922 -299.699934 -90)
		(property "Reference" "C1934"
			(at 0 0 90)
			(layer "B.SilkS")
			(hide yes)
			(effects
				(font
					(size 1.27 1.27)
				)
				(justify mirror)
			)
		)
		(property "Value" ""
			(at 0 0 90)
			(layer "B.Fab")
			(effects
				(font
					(size 1.27 1.27)
				)
				(justify mirror)
			)
		)
		(duplicate_pad_numbers_are_jumpers no)
		(fp_line
			(start -0.299974 0.150114)
			(end 0.299974 0.150114)
			(stroke
				(width 0.1)
				(type default)
			)
			(layer "B.Fab")
		)
		(fp_line
			(start 0.299974 0.150114)
			(end 0.299974 -0.150114)
			(stroke
				(width 0.1)
				(type default)
			)
			(layer "B.Fab")
		)
		(fp_line
			(start -0.299974 -0.150114)
			(end -0.299974 0.150114)
			(stroke
				(width 0.1)
				(type default)
			)
			(layer "B.Fab")
		)
		(fp_line
			(start 0.299974 -0.150114)
			(end -0.299974 -0.150114)
			(stroke
				(width 0.1)
				(type default)
			)
			(layer "B.Fab")
		)
		(pad "1" smd rect
			(at 0.2667 0 90)
			(size 0.3048 0.381)
			(layers "B.Cu" "B.Mask" "B.Paste")
			(net "P0V8_SERDES_VDDA_PEX3")
		)
		(pad "2" smd rect
			(at -0.2667 0 90)
			(size 0.3048 0.381)
			(layers "B.Cu" "B.Mask" "B.Paste")
			(net "GND")
		)
	)
	(footprint ""
		(layer "B.Cu")
		(at 65.349882 -290.199826 90)
		(property "Reference" "C1168"
			(at 0 0 90)
			(layer "B.SilkS")
			(hide yes)
			(effects
				(font
					(size 1.27 1.27)
				)
				(justify mirror)
			)
		)
		(property "Value" ""
			(at 0 0 90)
			(layer "B.Fab")
			(effects
				(font
					(size 1.27 1.27)
				)
				(justify mirror)
			)
		)
		(duplicate_pad_numbers_are_jumpers no)
		(fp_line
			(start 0.299974 -0.150114)
			(end -0.299974 -0.150114)
			(stroke
				(width 0.1)
				(type default)
			)
			(layer "B.Fab")
		)
		(fp_line
			(start -0.299974 -0.150114)
			(end -0.299974 0.150114)
			(stroke
				(width 0.1)
				(type default)
			)
			(layer "B.Fab")
		)
		(fp_line
			(start 0.299974 0.150114)
			(end 0.299974 -0.150114)
			(stroke
				(width 0.1)
				(type default)
			)
			(layer "B.Fab")
		)
		(fp_line
			(start -0.299974 0.150114)
			(end 0.299974 0.150114)
			(stroke
				(width 0.1)
				(type default)
			)
			(layer "B.Fab")
		)
		(pad "1" smd rect
			(at 0.2667 0 270)
			(size 0.3048 0.381)
			(layers "B.Cu" "B.Mask" "B.Paste")
			(net "P0V8_SERDES_VDDA_PEX0")
		)
		(pad "2" smd rect
			(at -0.2667 0 270)
			(size 0.3048 0.381)
			(layers "B.Cu" "B.Mask" "B.Paste")
			(net "GND")
		)
	)
	(footprint ""
		(layer "B.Cu")
		(at 210.691476 -246.686578 -90)
		(property "Reference" "R6338"
			(at 0 0 90)
			(layer "B.SilkS")
			(hide yes)
			(effects
				(font
					(size 1.27 1.27)
				)
				(justify mirror)
			)
		)
		(property "Value" ""
			(at 0 0 90)
			(layer "B.Fab")
			(effects
				(font
					(size 1.27 1.27)
				)
				(justify mirror)
			)
		)
		(duplicate_pad_numbers_are_jumpers no)
		(fp_line
			(start -0.7874 0.4064)
			(end 0.7874 0.4064)
			(stroke
				(width 0.1524)
				(type default)
			)
			(layer "B.SilkS")
		)
		(fp_line
			(start 0.7874 0.4064)
			(end 0.7874 -0.4064)
			(stroke
				(width 0.1524)
				(type default)
			)
			(layer "B.SilkS")
		)
		(fp_line
			(start -0.7874 -0.4064)
			(end -0.7874 0.4064)
			(stroke
				(width 0.1524)
				(type default)
			)
			(layer "B.SilkS")
		)
		(fp_line
			(start 0.7874 -0.4064)
			(end -0.7874 -0.4064)
			(stroke
				(width 0.1524)
				(type default)
			)
			(layer "B.SilkS")
		)
		(fp_line
			(start -0.67945 0.3048)
			(end -0.120396 0.3048)
			(stroke
				(width 0.1)
				(type default)
			)
			(layer "B.Fab")
		)
		(fp_line
			(start -0.120396 0.3048)
			(end -0.120396 0.2794)
			(stroke
				(width 0.1)
				(type default)
			)
			(layer "B.Fab")
		)
		(fp_line
			(start 0.12065 0.3048)
			(end 0.67945 0.3048)
			(stroke
				(width 0.1)
				(type default)
			)
			(layer "B.Fab")
		)
		(fp_line
			(start 0.67945 0.3048)
			(end 0.67945 -0.305054)
			(stroke
				(width 0.1)
				(type default)
			)
			(layer "B.Fab")
		)
		(fp_line
			(start -0.120396 0.2794)
			(end 0.12065 0.2794)
			(stroke
				(width 0.1)
				(type default)
			)
			(layer "B.Fab")
		)
		(fp_line
			(start 0.12065 0.2794)
			(end 0.12065 0.3048)
			(stroke
				(width 0.1)
				(type default)
			)
			(layer "B.Fab")
		)
		(fp_line
			(start -0.12065 -0.2794)
			(end -0.12065 -0.3048)
			(stroke
				(width 0.1)
				(type default)
			)
			(layer "B.Fab")
		)
		(fp_line
			(start 0.12065 -0.2794)
			(end -0.12065 -0.2794)
			(stroke
				(width 0.1)
				(type default)
			)
			(layer "B.Fab")
		)
		(fp_line
			(start -0.67945 -0.3048)
			(end -0.67945 0.3048)
			(stroke
				(width 0.1)
				(type default)
			)
			(layer "B.Fab")
		)
		(fp_line
			(start -0.12065 -0.3048)
			(end -0.67945 -0.3048)
			(stroke
				(width 0.1)
				(type default)
			)
			(layer "B.Fab")
		)
		(fp_line
			(start 0.12065 -0.305054)
			(end 0.12065 -0.2794)
			(stroke
				(width 0.1)
				(type default)
			)
			(layer "B.Fab")
		)
		(fp_line
			(start 0.67945 -0.305054)
			(end 0.12065 -0.305054)
			(stroke
				(width 0.1)
				(type default)
			)
			(layer "B.Fab")
		)
		(pad "1" smd circle
			(at 0.40005 0 90)
			(size 0 0)
			(layers "B.Cu" "B.Mask" "B.Paste")
			(net "P1V8_PEX")
		)
		(pad "2" smd circle
			(at -0.40005 0 90)
			(size 0 0)
			(layers "B.Cu" "B.Mask" "B.Paste")
			(net "PEX_MUX_A2")
		)
	)
	(footprint ""
		(layer "B.Cu")
		(at 24.120348 -220.932756 90)
		(property "Reference" "R3446"
			(at 0 0 90)
			(layer "B.SilkS")
			(hide yes)
			(effects
				(font
					(size 1.27 1.27)
				)
				(justify mirror)
			)
		)
		(property "Value" ""
			(at 0 0 90)
			(layer "B.Fab")
			(effects
				(font
					(size 1.27 1.27)
				)
				(justify mirror)
			)
		)
		(duplicate_pad_numbers_are_jumpers no)
		(fp_line
			(start 0.7874 -0.4064)
			(end -0.7874 -0.4064)
			(stroke
				(width 0.1524)
				(type default)
			)
			(layer "B.SilkS")
		)
		(fp_line
			(start -0.7874 -0.4064)
			(end -0.7874 0.4064)
			(stroke
				(width 0.1524)
				(type default)
			)
			(layer "B.SilkS")
		)
		(fp_line
			(start 0.7874 0.4064)
			(end 0.7874 -0.4064)
			(stroke
				(width 0.1524)
				(type default)
			)
			(layer "B.SilkS")
		)
		(fp_line
			(start -0.7874 0.4064)
			(end 0.7874 0.4064)
			(stroke
				(width 0.1524)
				(type default)
			)
			(layer "B.SilkS")
		)
		(fp_line
			(start 0.67945 -0.305054)
			(end 0.12065 -0.305054)
			(stroke
				(width 0.1)
				(type default)
			)
			(layer "B.Fab")
		)
		(fp_line
			(start 0.12065 -0.305054)
			(end 0.12065 -0.2794)
			(stroke
				(width 0.1)
				(type default)
			)
			(layer "B.Fab")
		)
		(fp_line
			(start -0.12065 -0.3048)
			(end -0.67945 -0.3048)
			(stroke
				(width 0.1)
				(type default)
			)
			(layer "B.Fab")
		)
		(fp_line
			(start -0.67945 -0.3048)
			(end -0.67945 0.3048)
			(stroke
				(width 0.1)
				(type default)
			)
			(layer "B.Fab")
		)
		(fp_line
			(start 0.12065 -0.2794)
			(end -0.12065 -0.2794)
			(stroke
				(width 0.1)
				(type default)
			)
			(layer "B.Fab")
		)
		(fp_line
			(start -0.12065 -0.2794)
			(end -0.12065 -0.3048)
			(stroke
				(width 0.1)
				(type default)
			)
			(layer "B.Fab")
		)
		(fp_line
			(start 0.12065 0.2794)
			(end 0.12065 0.3048)
			(stroke
				(width 0.1)
				(type default)
			)
			(layer "B.Fab")
		)
		(fp_line
			(start -0.120396 0.2794)
			(end 0.12065 0.2794)
			(stroke
				(width 0.1)
				(type default)
			)
			(layer "B.Fab")
		)
		(fp_line
			(start 0.67945 0.3048)
			(end 0.67945 -0.305054)
			(stroke
				(width 0.1)
				(type default)
			)
			(layer "B.Fab")
		)
		(fp_line
			(start 0.12065 0.3048)
			(end 0.67945 0.3048)
			(stroke
				(width 0.1)
				(type default)
			)
			(layer "B.Fab")
		)
		(fp_line
			(start -0.120396 0.3048)
			(end -0.120396 0.2794)
			(stroke
				(width 0.1)
				(type default)
			)
			(layer "B.Fab")
		)
		(fp_line
			(start -0.67945 0.3048)
			(end -0.120396 0.3048)
			(stroke
				(width 0.1)
				(type default)
			)
			(layer "B.Fab")
		)
		(pad "1" smd circle
			(at 0.40005 0 270)
			(size 0 0)
			(layers "B.Cu" "B.Mask" "B.Paste")
			(net "SPI_PEX0_SDIO3_R")
		)
		(pad "2" smd circle
			(at -0.40005 0 270)
			(size 0 0)
			(layers "B.Cu" "B.Mask" "B.Paste")
			(net "SPI_PEX0_SDIO3_R1")
		)
	)
	(footprint ""
		(layer "B.Cu")
		(at 420.05504 -98.552)
		(property "Reference" "R359"
			(at 0 0 0)
			(layer "B.SilkS")
			(hide yes)
			(effects
				(font
					(size 1.27 1.27)
				)
				(justify mirror)
			)
		)
		(property "Value" ""
			(at 0 0 0)
			(layer "B.Fab")
			(effects
				(font
					(size 1.27 1.27)
				)
				(justify mirror)
			)
		)
		(duplicate_pad_numbers_are_jumpers no)
		(fp_line
			(start -0.7874 -0.4064)
			(end -0.7874 0.4064)
			(stroke
				(width 0.1524)
				(type default)
			)
			(layer "B.SilkS")
		)
		(fp_line
			(start -0.7874 0.4064)
			(end 0.7874 0.4064)
			(stroke
				(width 0.1524)
				(type default)
			)
			(layer "B.SilkS")
		)
		(fp_line
			(start 0.7874 -0.4064)
			(end -0.7874 -0.4064)
			(stroke
				(width 0.1524)
				(type default)
			)
			(layer "B.SilkS")
		)
		(fp_line
			(start 0.7874 0.4064)
			(end 0.7874 -0.4064)
			(stroke
				(width 0.1524)
				(type default)
			)
			(layer "B.SilkS")
		)
		(fp_line
			(start -0.67945 -0.3048)
			(end -0.67945 0.3048)
			(stroke
				(width 0.1)
				(type default)
			)
			(layer "B.Fab")
		)
		(fp_line
			(start -0.67945 0.3048)
			(end -0.120396 0.3048)
			(stroke
				(width 0.1)
				(type default)
			)
			(layer "B.Fab")
		)
		(fp_line
			(start -0.12065 -0.3048)
			(end -0.67945 -0.3048)
			(stroke
				(width 0.1)
				(type default)
			)
			(layer "B.Fab")
		)
		(fp_line
			(start -0.12065 -0.2794)
			(end -0.12065 -0.3048)
			(stroke
				(width 0.1)
				(type default)
			)
			(layer "B.Fab")
		)
		(fp_line
			(start -0.120396 0.2794)
			(end 0.12065 0.2794)
			(stroke
				(width 0.1)
				(type default)
			)
			(layer "B.Fab")
		)
		(fp_line
			(start -0.120396 0.3048)
			(end -0.120396 0.2794)
			(stroke
				(width 0.1)
				(type default)
			)
			(layer "B.Fab")
		)
		(fp_line
			(start 0.12065 -0.305054)
			(end 0.12065 -0.2794)
			(stroke
				(width 0.1)
				(type default)
			)
			(layer "B.Fab")
		)
		(fp_line
			(start 0.12065 -0.2794)
			(end -0.12065 -0.2794)
			(stroke
				(width 0.1)
				(type default)
			)
			(layer "B.Fab")
		)
		(fp_line
			(start 0.12065 0.2794)
			(end 0.12065 0.3048)
			(stroke
				(width 0.1)
				(type default)
			)
			(layer "B.Fab")
		)
		(fp_line
			(start 0.12065 0.3048)
			(end 0.67945 0.3048)
			(stroke
				(width 0.1)
				(type default)
			)
			(layer "B.Fab")
		)
		(fp_line
			(start 0.67945 -0.305054)
			(end 0.12065 -0.305054)
			(stroke
				(width 0.1)
				(type default)
			)
			(layer "B.Fab")
		)
		(fp_line
			(start 0.67945 0.3048)
			(end 0.67945 -0.305054)
			(stroke
				(width 0.1)
				(type default)
			)
			(layer "B.Fab")
		)
		(pad "1" smd circle
			(at 0.40005 0 180)
			(size 0 0)
			(layers "B.Cu" "B.Mask" "B.Paste")
			(net "NIC7_MAIN_PWR_EN_R")
		)
		(pad "2" smd circle
			(at -0.40005 0 180)
			(size 0 0)
			(layers "B.Cu" "B.Mask" "B.Paste")
			(net "NIC7_MAIN_PWR_EN")
		)
	)
)
